#ISCELL
  mstr_misc dns *
  *
#ISCELL
  mstr_symbols intel_corp_bpage *
  *
#ISCELL
  mstr_symbols pvddq_klm *
  page227_i1
#CELL
  mstr_discrete ir354xx *
  page227_i101
#CELL
  mstr_discrete ir354xx *
  page227_i102
#CELL
  mstr_discrete res *
  page227_i103
#ISCELL
  mstr_symbols gnd *
  page227_i104
#CELL
  mstr_discrete res *
  page227_i105
#ISCELL
  mstr_symbols gnd *
  page227_i106
#ISCELL
  mstr_symbols p5v_stby *
  page227_i107
#CELL
  dev_discrete cap_a *
  page227_i109
#ISCELL
  mstr_symbols gnd *
  page227_i110
#CELL
  w_hdl sc2k2p50v3kx-gp *
  page227_i111
#ISCELL
  mstr_symbols gnd *
  page227_i113
#CELL
  mstr_discrete cap *
  page227_i114
#ISCELL
  mstr_symbols gnd *
  page227_i115
#CELL
  w_hdl sc2k2p50v3kx-gp *
  page227_i116
#ISCELL
  mstr_symbols gnd *
  page227_i117
#CELL
  mstr_discrete cap *
  page227_i119
#ISCELL
  mstr_symbols gnd *
  page227_i120
#CELL
  dev_discrete cap_a *
  page227_i122
#ISCELL
  mstr_symbols gnd *
  page227_i123
#CELL
  w_hdl 3d01r5f-gp *
  page227_i124
#CELL
  w_hdl 3d01r5f-gp *
  page227_i125
#CELL
  mstr_discrete res *
  page227_i126
#CELL
  mstr_discrete res *
  page227_i127
#ISCELL
  mstr_symbols gnd *
  page227_i19
#ISCELL
  mstr_standard offpage *
  page227_i3
#ISCELL
  mstr_standard offpage *
  page227_i33
#ISCELL
  mstr_symbols gnd *
  page227_i35
#ISCELL
  mstr_standard offpage *
  page227_i4
#CELL
  mstr_discrete cap *
  page227_i44
#CELL
  mstr_discrete cap *
  page227_i45
#CELL
  mstr_discrete cap *
  page227_i46
#CELL
  mstr_discrete cap *
  page227_i47
#CELL
  mstr_discrete cap *
  page227_i48
#CELL
  mstr_discrete cap *
  page227_i50
#CELL
  dev_discrete cap_a *
  page227_i51
#CELL
  mstr_discrete res *
  page227_i52
#CELL
  dev_discrete cap_a *
  page227_i53
#CELL
  mstr_discrete cap *
  page227_i54
#CELL
  mstr_discrete inductor *
  page227_i55
#ISCELL
  mstr_standard offpage *
  page227_i58
#CELL
  mstr_discrete cap *
  page227_i6
#ISCELL
  mstr_standard offpage *
  page227_i61
#ISCELL
  mstr_standard offpage *
  page227_i62
#ISCELL
  mstr_standard offpage *
  page227_i63
#ISCELL
  mstr_symbols pvddq_klm *
  page227_i64
#CELL
  mstr_discrete inductor *
  page227_i65
#CELL
  mstr_discrete cap *
  page227_i68
#ISCELL
  mstr_symbols gnd *
  page227_i69
#ISCELL
  mstr_symbols gnd *
  page227_i7
#ISCELL
  mstr_symbols gnd *
  page227_i70
#CELL
  mstr_discrete cap *
  page227_i72
#CELL
  dev_discrete cap_a *
  page227_i73
#CELL
  mstr_discrete cap *
  page227_i75
#CELL
  mstr_discrete res *
  page227_i76
#CELL
  mstr_discrete cap *
  page227_i77
#CELL
  dev_discrete cap_a *
  page227_i78
#CELL
  mstr_discrete cap *
  page227_i79
#CELL
  mstr_discrete cap *
  page227_i80
#CELL
  mstr_discrete cap *
  page227_i81
#ISCELL
  mstr_standard offpage *
  page227_i82
#ISCELL
  mstr_symbols vcc_core *
  page227_i83
#CELL
  mstr_discrete cap *
  page227_i84
#ISCELL
  mstr_symbols gnd *
  page227_i85
#ISCELL
  mstr_symbols vcc_core *
  page227_i86
#ISCELL
  mstr_symbols p5v_stby *
  page227_i88
